# T6G (Grand Teton) — schematic netlist excerpt (pin names and nets, part order shuffled) for the footprints in the layout excerpt that follows; sources: Cadence DE-HDL packaged netlist, KiCad conversion of 04192023_DAF0TMB3IC0_F0TG_MB_C_brd_V02_OCP.brd

R1854  Q_RES  1K 1% CHIP  pkg 0402LF  page 152 : A = P3V3_AUX ; B = FM_SCM_PRSNT1_N
PC596  Q_CAPP  270UF 16V 20% OSCON  pkg THLF  page 198 : A = SW_P12V_AUX_PVDDCR_SOC_P0_FLT ; B = GND
R318  Q_RES  10K 1% EMPTY  pkg 0402LF  page 250 : A = P3V3_AUX ; B = PCA9548_PCIE3_ADDR1

(kicad_pcb
	(version 20260206)
	(generator "pcbnew")
	(generator_version "10.0")
	(general
		(thickness 1.6)
		(legacy_teardrops no)
	)
	(paper "A4")
	(title_block
		(title "04192023_DAF0TMB3IC0_F0TG_MB_C_brd_V02_OCP.brd")
		(comment 1 "Grand Teton / footprints 4552-4554 of 8354")
	)
	(layers
		(0 "F.Cu" signal "TOP")
		(4 "In1.Cu" signal "GND")
		(6 "In2.Cu" signal "IN1")
		(8 "In3.Cu" signal "GND1")
		(10 "In4.Cu" signal "IN2")
		(12 "In5.Cu" signal "GND2")
		(14 "In6.Cu" signal "IN3")
		(16 "In7.Cu" signal "GND3")
		(18 "In8.Cu" signal "VCC")
		(20 "In9.Cu" signal "VCC1")
		(22 "In10.Cu" signal "GND4")
		(24 "In11.Cu" signal "IN4")
		(26 "In12.Cu" signal "GND5")
		(28 "In13.Cu" signal "IN5")
		(30 "In14.Cu" signal "GND6")
		(32 "In15.Cu" signal "IN6")
		(34 "In16.Cu" signal "GND7")
		(2 "B.Cu" signal "BOTTOM")
		(9 "F.Adhes" user "F.Adhesive")
		(11 "B.Adhes" user "B.Adhesive")
		(13 "F.Paste" user "Package Geometry/Pastemask Top")
		(15 "B.Paste" user "Package Geometry/Pastemask Bottom")
		(5 "F.SilkS" user "Ref Des/Silkscreen Top")
		(7 "B.SilkS" user "Ref Des/Silkscreen Bottom")
		(1 "F.Mask" user "Board Geometry/Soldermask Top")
		(3 "B.Mask" user "Board Geometry/Soldermask Bottom")
		(17 "Dwgs.User" user "User.Drawings")
		(19 "Cmts.User" user "User.Comments")
		(21 "Eco1.User" user "User.Eco1")
		(23 "Eco2.User" user "User.Eco2")
		(25 "Edge.Cuts" user "Board Geometry/Outline")
		(27 "Margin" user)
		(31 "F.CrtYd" user "Package Geometry/Place Bound Top")
		(29 "B.CrtYd" user "Package Geometry/Place Bound Bottom")
		(35 "F.Fab" user "Ref Des/Assembly Top")
		(33 "B.Fab" user "Ref Des/Assembly Bottom")
	)
	(footprint ""
		(layer "F.Cu")
		(at 189.80023 -35.017456 180)
		(property "Reference" "R1854"
			(at 0 0 180)
			(layer "F.SilkS")
			(hide yes)
			(effects
				(font
					(size 1.27 1.27)
				)
			)
		)
		(property "Value" ""
			(at 0 0 180)
			(layer "F.Fab")
			(effects
				(font
					(size 1.27 1.27)
				)
			)
		)
		(duplicate_pad_numbers_are_jumpers no)
		(fp_line
			(start 0.7874 0.4064)
			(end -0.7874 0.4064)
			(stroke
				(width 0.1524)
				(type default)
			)
			(layer "F.SilkS")
		)
		(fp_line
			(start 0.7874 -0.4064)
			(end 0.7874 0.4064)
			(stroke
				(width 0.1524)
				(type default)
			)
			(layer "F.SilkS")
		)
		(fp_line
			(start -0.7874 0.4064)
			(end -0.7874 -0.4064)
			(stroke
				(width 0.1524)
				(type default)
			)
			(layer "F.SilkS")
		)
		(fp_line
			(start -0.7874 -0.4064)
			(end 0.7874 -0.4064)
			(stroke
				(width 0.1524)
				(type default)
			)
			(layer "F.SilkS")
		)
		(fp_line
			(start 0.67945 0.3048)
			(end 0.120396 0.3048)
			(stroke
				(width 0.1)
				(type default)
			)
			(layer "F.Fab")
		)
		(fp_line
			(start 0.67945 -0.3048)
			(end 0.67945 0.3048)
			(stroke
				(width 0.1)
				(type default)
			)
			(layer "F.Fab")
		)
		(fp_line
			(start 0.12065 -0.2794)
			(end 0.12065 -0.3048)
			(stroke
				(width 0.1)
				(type default)
			)
			(layer "F.Fab")
		)
		(fp_line
			(start 0.12065 -0.3048)
			(end 0.67945 -0.3048)
			(stroke
				(width 0.1)
				(type default)
			)
			(layer "F.Fab")
		)
		(fp_line
			(start 0.120396 0.3048)
			(end 0.120396 0.2794)
			(stroke
				(width 0.1)
				(type default)
			)
			(layer "F.Fab")
		)
		(fp_line
			(start 0.120396 0.2794)
			(end -0.12065 0.2794)
			(stroke
				(width 0.1)
				(type default)
			)
			(layer "F.Fab")
		)
		(fp_line
			(start -0.12065 0.3048)
			(end -0.67945 0.3048)
			(stroke
				(width 0.1)
				(type default)
			)
			(layer "F.Fab")
		)
		(fp_line
			(start -0.12065 0.2794)
			(end -0.12065 0.3048)
			(stroke
				(width 0.1)
				(type default)
			)
			(layer "F.Fab")
		)
		(fp_line
			(start -0.12065 -0.2794)
			(end 0.12065 -0.2794)
			(stroke
				(width 0.1)
				(type default)
			)
			(layer "F.Fab")
		)
		(fp_line
			(start -0.12065 -0.305054)
			(end -0.12065 -0.2794)
			(stroke
				(width 0.1)
				(type default)
			)
			(layer "F.Fab")
		)
		(fp_line
			(start -0.67945 0.3048)
			(end -0.67945 -0.305054)
			(stroke
				(width 0.1)
				(type default)
			)
			(layer "F.Fab")
		)
		(fp_line
			(start -0.67945 -0.305054)
			(end -0.12065 -0.305054)
			(stroke
				(width 0.1)
				(type default)
			)
			(layer "F.Fab")
		)
		(pad "1" smd circle
			(at -0.40005 0 180)
			(size 0 0)
			(layers "F.Cu" "F.Mask" "F.Paste")
			(net "P3V3_AUX")
		)
		(pad "2" smd circle
			(at 0.40005 0 180)
			(size 0 0)
			(layers "F.Cu" "F.Mask" "F.Paste")
			(net "FM_SCM_PRSNT1_N")
		)
	)
	(footprint ""
		(layer "F.Cu")
		(at 277.352252 -124.368814)
		(property "Reference" "R318"
			(at 0 0 0)
			(layer "F.SilkS")
			(hide yes)
			(effects
				(font
					(size 1.27 1.27)
				)
			)
		)
		(property "Value" ""
			(at 0 0 0)
			(layer "F.Fab")
			(effects
				(font
					(size 1.27 1.27)
				)
			)
		)
		(duplicate_pad_numbers_are_jumpers no)
		(fp_line
			(start -0.7874 -0.4064)
			(end 0.7874 -0.4064)
			(stroke
				(width 0.1524)
				(type default)
			)
			(layer "F.SilkS")
		)
		(fp_line
			(start -0.7874 0.4064)
			(end -0.7874 -0.4064)
			(stroke
				(width 0.1524)
				(type default)
			)
			(layer "F.SilkS")
		)
		(fp_line
			(start 0.7874 -0.4064)
			(end 0.7874 0.4064)
			(stroke
				(width 0.1524)
				(type default)
			)
			(layer "F.SilkS")
		)
		(fp_line
			(start 0.7874 0.4064)
			(end -0.7874 0.4064)
			(stroke
				(width 0.1524)
				(type default)
			)
			(layer "F.SilkS")
		)
		(fp_line
			(start -0.67945 -0.305054)
			(end -0.12065 -0.305054)
			(stroke
				(width 0.1)
				(type default)
			)
			(layer "F.Fab")
		)
		(fp_line
			(start -0.67945 0.3048)
			(end -0.67945 -0.305054)
			(stroke
				(width 0.1)
				(type default)
			)
			(layer "F.Fab")
		)
		(fp_line
			(start -0.12065 -0.305054)
			(end -0.12065 -0.2794)
			(stroke
				(width 0.1)
				(type default)
			)
			(layer "F.Fab")
		)
		(fp_line
			(start -0.12065 -0.2794)
			(end 0.12065 -0.2794)
			(stroke
				(width 0.1)
				(type default)
			)
			(layer "F.Fab")
		)
		(fp_line
			(start -0.12065 0.2794)
			(end -0.12065 0.3048)
			(stroke
				(width 0.1)
				(type default)
			)
			(layer "F.Fab")
		)
		(fp_line
			(start -0.12065 0.3048)
			(end -0.67945 0.3048)
			(stroke
				(width 0.1)
				(type default)
			)
			(layer "F.Fab")
		)
		(fp_line
			(start 0.120396 0.2794)
			(end -0.12065 0.2794)
			(stroke
				(width 0.1)
				(type default)
			)
			(layer "F.Fab")
		)
		(fp_line
			(start 0.120396 0.3048)
			(end 0.120396 0.2794)
			(stroke
				(width 0.1)
				(type default)
			)
			(layer "F.Fab")
		)
		(fp_line
			(start 0.12065 -0.3048)
			(end 0.67945 -0.3048)
			(stroke
				(width 0.1)
				(type default)
			)
			(layer "F.Fab")
		)
		(fp_line
			(start 0.12065 -0.2794)
			(end 0.12065 -0.3048)
			(stroke
				(width 0.1)
				(type default)
			)
			(layer "F.Fab")
		)
		(fp_line
			(start 0.67945 -0.3048)
			(end 0.67945 0.3048)
			(stroke
				(width 0.1)
				(type default)
			)
			(layer "F.Fab")
		)
		(fp_line
			(start 0.67945 0.3048)
			(end 0.120396 0.3048)
			(stroke
				(width 0.1)
				(type default)
			)
			(layer "F.Fab")
		)
		(pad "1" smd circle
			(at -0.40005 0)
			(size 0 0)
			(layers "F.Cu" "F.Mask" "F.Paste")
			(net "P3V3_AUX")
		)
		(pad "2" smd circle
			(at 0.40005 0)
			(size 0 0)
			(layers "F.Cu" "F.Mask" "F.Paste")
			(net "PCA9548_PCIE3_ADDR1")
		)
	)
	(footprint ""
		(layer "F.Cu")
		(at 387.206998 -162.65271 180)
		(property "Reference" "PC596"
			(at 1.796796 -2.887472 0)
			(unlocked yes)
			(layer "F.SilkS")
			(effects
				(font
					(size 0.7874 0.5842)
					(thickness 0.1524)
				)
				(justify left)
			)
		)
		(property "Value" ""
			(at 0 0 180)
			(layer "F.Fab")
			(effects
				(font
					(size 1.27 1.27)
				)
			)
		)
		(duplicate_pad_numbers_are_jumpers no)
		(fp_line
			(start -3.400044 1.249934)
			(end 3.400044 1.249934)
			(stroke
				(width 0.1524)
				(type default)
			)
			(layer "F.SilkS")
		)
		(fp_circle
			(center 0 1.249934)
			(end -3.400044 1.249934)
			(stroke
				(width 0.1524)
				(type default)
			)
			(fill no)
			(layer "F.SilkS")
		)
		(fp_poly
			(pts
				(arc
					(start 3.400044 1.249934)
					(mid 0 4.649978)
					(end -3.400044 1.249934)
				)
			)
			(stroke
				(width 0)
				(type default)
			)
			(fill yes)
			(layer "F.SilkS")
		)
		(fp_circle
			(center 0 1.249934)
			(end -3.400044 1.249934)
			(stroke
				(width 0.1)
				(type default)
			)
			(fill no)
			(layer "F.Fab")
		)
		(pad "1" thru_hole rect
			(at 0 0 180)
			(size 1.524 1.524)
			(drill 1.016)
			(layers "*.Cu" "*.Mask")
			(remove_unused_layers no)
			(net "SW_P12V_AUX_PVDDCR_SOC_P0_FLT")
			(clearance 0)
			(padstack
				(mode front_inner_back)
				(layer "Inner"
					(shape circle)
					(size 1.524 1.524)
					(clearance 0)
				)
				(layer "B.Cu"
					(shape rect)
					(size 1.524 1.524)
					(clearance 0)
				)
			)
		)
		(pad "2" thru_hole circle
			(at 0 2.500122 180)
			(size 1.524 1.524)
			(drill 1.016)
			(layers "*.Cu" "*.Mask")
			(remove_unused_layers no)
			(net "GND")
			(clearance 0)
		)
	)
)
